(kicad_pcb
	(version 20260206)
	(generator "pcbnew")
	(generator_version "10.0")
	(general
		(thickness 1.6)
		(legacy_teardrops no)
	)
	(paper "A4")
	(title_block
		(title "peb — Lightning_PEB_BRD.brd")
		(comment 1 "Lightning (Wiwynn / Facebook NVMe JBOF) / footprints 1846-1854 of 2563")
	)
	(layers
		(0 "F.Cu" signal "TOP")
		(4 "In1.Cu" signal "L2GND")
		(6 "In2.Cu" signal "L3")
		(8 "In3.Cu" signal "L4VCC")
		(10 "In4.Cu" signal "L5VCC")
		(12 "In5.Cu" signal "L6")
		(14 "In6.Cu" signal "L7GND")
		(2 "B.Cu" signal "BOTTOM")
		(9 "F.Adhes" user "F.Adhesive")
		(11 "B.Adhes" user "B.Adhesive")
		(13 "F.Paste" user "Package Geometry/Pastemask Top")
		(15 "B.Paste" user "Package Geometry/Pastemask Bottom")
		(5 "F.SilkS" user "Ref Des/Silkscreen Top")
		(7 "B.SilkS" user "Ref Des/Silkscreen Bottom")
		(1 "F.Mask" user "Board Geometry/Soldermask Top")
		(3 "B.Mask" user "Board Geometry/Soldermask Bottom")
		(17 "Dwgs.User" user "User.Drawings")
		(19 "Cmts.User" user "User.Comments")
		(21 "Eco1.User" user "User.Eco1")
		(23 "Eco2.User" user "User.Eco2")
		(25 "Edge.Cuts" user "Board Geometry/Outline")
		(27 "Margin" user)
		(31 "F.CrtYd" user "Package Geometry/Place Bound Top")
		(29 "B.CrtYd" user "Package Geometry/Place Bound Bottom")
		(35 "F.Fab" user "Ref Des/Assembly Top")
		(33 "B.Fab" user "Ref Des/Assembly Bottom")
	)
	(footprint ""
		(layer "B.Cu")
		(at 41.656 -128.397 -90)
		(property "Reference" "C215"
			(at 0 0 90)
			(layer "B.SilkS")
			(hide yes)
			(effects
				(font
					(size 1.27 1.27)
				)
				(justify mirror)
			)
		)
		(property "Value" "SC1U10V2KX-4-GP"
			(at -1.1811 -2.7051 270)
			(unlocked yes)
			(layer "B.Fab")
			(hide yes)
			(effects
				(font
					(size 1.016 1.016)
					(thickness 0.1524)
				)
				(justify mirror)
			)
		)
		(property "Device Type" "C402H22"
			(at -1.1811 -4.2291 270)
			(unlocked yes)
			(layer "B.Fab")
			(hide yes)
			(effects
				(font
					(size 1.016 1.016)
					(thickness 0.1524)
				)
				(justify mirror)
			)
		)
		(duplicate_pad_numbers_are_jumpers no)
		(fp_rect
			(start 0.4318 0.9525)
			(end -0.4318 -0.9525)
			(stroke
				(width 0)
				(type default)
			)
			(fill no)
			(layer "B.CrtYd")
		)
		(fp_rect
			(start 0.4318 0.9525)
			(end -0.4318 -0.9525)
			(stroke
				(width 0)
				(type default)
			)
			(fill no)
			(layer "B.Fab")
		)
		(pad "1" smd custom
			(at 0 -0.4445 90)
			(size 0.1524 0.1524)
			(layers "B.Cu" "B.Mask" "B.Paste")
			(net "P3V3_STBY")
			(options
				(clearance outline)
				(anchor circle)
			)
			(primitives
				(gr_poly
					(pts
						(arc
							(start 0.3048 0.2032)
							(mid 0.275042 0.275042)
							(end 0.2032 0.3048)
						)
						(arc
							(start -0.2032 0.3048)
							(mid -0.275042 0.275042)
							(end -0.3048 0.2032)
						)
						(arc
							(start -0.3048 -0.2032)
							(mid -0.275042 -0.275042)
							(end -0.2032 -0.3048)
						)
						(arc
							(start 0.2032 -0.3048)
							(mid 0.275042 -0.275042)
							(end 0.3048 -0.2032)
						)
					)
					(width 0)
					(fill yes)
				)
			)
		)
		(pad "2" smd custom
			(at 0 0.4445 90)
			(size 0.1524 0.1524)
			(layers "B.Cu" "B.Mask" "B.Paste")
			(net "GND")
			(options
				(clearance outline)
				(anchor circle)
			)
			(primitives
				(gr_poly
					(pts
						(arc
							(start 0.3048 0.2032)
							(mid 0.275042 0.275042)
							(end 0.2032 0.3048)
						)
						(arc
							(start -0.2032 0.3048)
							(mid -0.275042 0.275042)
							(end -0.3048 0.2032)
						)
						(arc
							(start -0.3048 -0.2032)
							(mid -0.275042 -0.275042)
							(end -0.2032 -0.3048)
						)
						(arc
							(start 0.2032 -0.3048)
							(mid 0.275042 -0.275042)
							(end 0.3048 -0.2032)
						)
					)
					(width 0)
					(fill yes)
				)
			)
		)
	)
	(footprint ""
		(layer "B.Cu")
		(at 42.824146 -133.914134)
		(property "Reference" "TP159"
			(at 0 0 0)
			(layer "B.SilkS")
			(hide yes)
			(effects
				(font
					(size 1.27 1.27)
				)
				(justify mirror)
			)
		)
		(property "Value" "TPAD28-2-GP"
			(at 0.0127 -1.6637 0)
			(unlocked yes)
			(layer "B.Fab")
			(hide yes)
			(effects
				(font
					(size 1.016 1.016)
					(thickness 0.1524)
				)
				(justify mirror)
			)
		)
		(property "Device Type" "TPAD28"
			(at 0.0127 -3.1877 0)
			(unlocked yes)
			(layer "B.Fab")
			(hide yes)
			(effects
				(font
					(size 1.016 1.016)
					(thickness 0.1524)
				)
				(justify mirror)
			)
		)
		(duplicate_pad_numbers_are_jumpers no)
		(fp_poly
			(pts
				(arc
					(start 0.3556 0)
					(mid -0.3556 0)
					(end 0.3556 0)
				)
			)
			(stroke
				(width 0)
				(type default)
			)
			(fill no)
			(layer "B.CrtYd")
		)
		(fp_poly
			(pts
				(arc
					(start 0.6096 0)
					(mid -0.6096 0)
					(end 0.6096 0)
				)
			)
			(stroke
				(width 0)
				(type default)
			)
			(fill no)
			(layer "B.Fab")
		)
		(pad "1" smd circle
			(at 0 0 180)
			(size 0.7112 0.7112)
			(layers "B.Cu" "B.Mask" "B.Paste")
			(net "TP_BMC_GPIOJ4")
		)
	)
	(footprint ""
		(layer "B.Cu")
		(at 345.186 -71.501 180)
		(property "Reference" "PR163"
			(at 0 0 0)
			(layer "B.SilkS")
			(hide yes)
			(effects
				(font
					(size 1.27 1.27)
				)
				(justify mirror)
			)
		)
		(property "Value" "100KR2F-L1-GP"
			(at -0.064008 -3.993896 180)
			(unlocked yes)
			(layer "B.Fab")
			(hide yes)
			(effects
				(font
					(size 1.016 1.016)
					(thickness 0.1524)
				)
				(justify mirror)
			)
		)
		(property "Device Type" "R402H16"
			(at -0.064008 -5.517896 180)
			(unlocked yes)
			(layer "B.Fab")
			(hide yes)
			(effects
				(font
					(size 1.016 1.016)
					(thickness 0.1524)
				)
				(justify mirror)
			)
		)
		(duplicate_pad_numbers_are_jumpers no)
		(fp_line
			(start 0.508 -0.9398)
			(end 0.508 0.9398)
			(stroke
				(width 0.1524)
				(type default)
			)
			(layer "B.SilkS")
		)
		(fp_line
			(start -0.508 -0.9398)
			(end 0.508 -0.9398)
			(stroke
				(width 0.1524)
				(type default)
			)
			(layer "B.SilkS")
		)
		(fp_rect
			(start 0.508 0.9398)
			(end -0.508 -0.9398)
			(stroke
				(width 0)
				(type default)
			)
			(fill no)
			(layer "B.CrtYd")
		)
		(fp_rect
			(start 0.508 0.9398)
			(end -0.508 -0.9398)
			(stroke
				(width 0)
				(type default)
			)
			(fill no)
			(layer "B.Fab")
		)
		(pad "1" smd custom
			(at 0 -0.4445)
			(size 0.1397 0.1397)
			(layers "B.Cu" "B.Mask" "B.Paste")
			(net "P0V9_E_MODE")
			(options
				(clearance outline)
				(anchor circle)
			)
			(primitives
				(gr_poly
					(pts
						(arc
							(start -0.1778 0.2794)
							(mid -0.249642 0.249642)
							(end -0.2794 0.1778)
						)
						(arc
							(start -0.2794 -0.1778)
							(mid -0.249642 -0.249642)
							(end -0.1778 -0.2794)
						)
						(arc
							(start 0.1778 -0.2794)
							(mid 0.249642 -0.249642)
							(end 0.2794 -0.1778)
						)
						(arc
							(start 0.2794 0.1778)
							(mid 0.249642 0.249642)
							(end 0.1778 0.2794)
						)
					)
					(width 0)
					(fill yes)
				)
			)
		)
		(pad "2" smd custom
			(at 0 0.4445)
			(size 0.1397 0.1397)
			(layers "B.Cu" "B.Mask" "B.Paste")
			(net "AGND_P0V9_E")
			(options
				(clearance outline)
				(anchor circle)
			)
			(primitives
				(gr_poly
					(pts
						(arc
							(start -0.1778 0.2794)
							(mid -0.249642 0.249642)
							(end -0.2794 0.1778)
						)
						(arc
							(start -0.2794 -0.1778)
							(mid -0.249642 -0.249642)
							(end -0.1778 -0.2794)
						)
						(arc
							(start 0.1778 -0.2794)
							(mid 0.249642 -0.249642)
							(end 0.2794 -0.1778)
						)
						(arc
							(start 0.2794 0.1778)
							(mid 0.249642 0.249642)
							(end 0.1778 0.2794)
						)
					)
					(width 0)
					(fill yes)
				)
			)
		)
	)
	(footprint ""
		(layer "B.Cu")
		(at 23.796498 -127.021336 90)
		(property "Reference" "R360"
			(at 0 0 90)
			(layer "B.SilkS")
			(hide yes)
			(effects
				(font
					(size 1.27 1.27)
				)
				(justify mirror)
			)
		)
		(property "Value" "3K3R2F-2-GP"
			(at -0.064008 -3.993896 90)
			(unlocked yes)
			(layer "B.Fab")
			(hide yes)
			(effects
				(font
					(size 1.016 1.016)
					(thickness 0.1524)
				)
				(justify mirror)
			)
		)
		(property "Device Type" "R402H16"
			(at -0.064008 -5.517896 90)
			(unlocked yes)
			(layer "B.Fab")
			(hide yes)
			(effects
				(font
					(size 1.016 1.016)
					(thickness 0.1524)
				)
				(justify mirror)
			)
		)
		(duplicate_pad_numbers_are_jumpers no)
		(fp_line
			(start 0.508 -0.9398)
			(end 0.508 0.9398)
			(stroke
				(width 0.1524)
				(type default)
			)
			(layer "B.SilkS")
		)
		(fp_line
			(start -0.508 -0.9398)
			(end 0.508 -0.9398)
			(stroke
				(width 0.1524)
				(type default)
			)
			(layer "B.SilkS")
		)
		(fp_rect
			(start 0.508 0.9398)
			(end -0.508 -0.9398)
			(stroke
				(width 0)
				(type default)
			)
			(fill no)
			(layer "B.CrtYd")
		)
		(fp_rect
			(start 0.508 0.9398)
			(end -0.508 -0.9398)
			(stroke
				(width 0)
				(type default)
			)
			(fill no)
			(layer "B.Fab")
		)
		(pad "1" smd custom
			(at 0 -0.4445 270)
			(size 0.1397 0.1397)
			(layers "B.Cu" "B.Mask" "B.Paste")
			(net "P3V3_STBY")
			(options
				(clearance outline)
				(anchor circle)
			)
			(primitives
				(gr_poly
					(pts
						(arc
							(start -0.1778 0.2794)
							(mid -0.249642 0.249642)
							(end -0.2794 0.1778)
						)
						(arc
							(start -0.2794 -0.1778)
							(mid -0.249642 -0.249642)
							(end -0.1778 -0.2794)
						)
						(arc
							(start 0.1778 -0.2794)
							(mid 0.249642 -0.249642)
							(end 0.2794 -0.1778)
						)
						(arc
							(start 0.2794 0.1778)
							(mid 0.249642 0.249642)
							(end 0.1778 0.2794)
						)
					)
					(width 0)
					(fill yes)
				)
			)
		)
		(pad "2" smd custom
			(at 0 0.4445 270)
			(size 0.1397 0.1397)
			(layers "B.Cu" "B.Mask" "B.Paste")
			(net "ROMA13")
			(options
				(clearance outline)
				(anchor circle)
			)
			(primitives
				(gr_poly
					(pts
						(arc
							(start -0.1778 0.2794)
							(mid -0.249642 0.249642)
							(end -0.2794 0.1778)
						)
						(arc
							(start -0.2794 -0.1778)
							(mid -0.249642 -0.249642)
							(end -0.1778 -0.2794)
						)
						(arc
							(start 0.1778 -0.2794)
							(mid 0.249642 -0.249642)
							(end 0.2794 -0.1778)
						)
						(arc
							(start 0.2794 0.1778)
							(mid 0.249642 0.249642)
							(end 0.1778 0.2794)
						)
					)
					(width 0)
					(fill yes)
				)
			)
		)
	)
	(footprint ""
		(layer "B.Cu")
		(at 140.58392 -34.934652 90)
		(property "Reference" "C227"
			(at 0 0 90)
			(layer "B.SilkS")
			(hide yes)
			(effects
				(font
					(size 1.27 1.27)
				)
				(justify mirror)
			)
		)
		(property "Value" "SCD1U10V2KX-5GP"
			(at -1.1811 -2.7051 90)
			(unlocked yes)
			(layer "B.Fab")
			(hide yes)
			(effects
				(font
					(size 1.016 1.016)
					(thickness 0.1524)
				)
				(justify mirror)
			)
		)
		(property "Device Type" "C402H22"
			(at -1.1811 -4.2291 90)
			(unlocked yes)
			(layer "B.Fab")
			(hide yes)
			(effects
				(font
					(size 1.016 1.016)
					(thickness 0.1524)
				)
				(justify mirror)
			)
		)
		(duplicate_pad_numbers_are_jumpers no)
		(fp_rect
			(start 0.4318 0.9525)
			(end -0.4318 -0.9525)
			(stroke
				(width 0)
				(type default)
			)
			(fill no)
			(layer "B.CrtYd")
		)
		(fp_rect
			(start 0.4318 0.9525)
			(end -0.4318 -0.9525)
			(stroke
				(width 0)
				(type default)
			)
			(fill no)
			(layer "B.Fab")
		)
		(pad "1" smd custom
			(at 0 -0.4445 270)
			(size 0.1524 0.1524)
			(layers "B.Cu" "B.Mask" "B.Paste")
			(net "GND")
			(options
				(clearance outline)
				(anchor circle)
			)
			(primitives
				(gr_poly
					(pts
						(arc
							(start 0.3048 0.2032)
							(mid 0.275042 0.275042)
							(end 0.2032 0.3048)
						)
						(arc
							(start -0.2032 0.3048)
							(mid -0.275042 0.275042)
							(end -0.3048 0.2032)
						)
						(arc
							(start -0.3048 -0.2032)
							(mid -0.275042 -0.275042)
							(end -0.2032 -0.3048)
						)
						(arc
							(start 0.2032 -0.3048)
							(mid 0.275042 -0.275042)
							(end 0.3048 -0.2032)
						)
					)
					(width 0)
					(fill yes)
				)
			)
		)
		(pad "2" smd custom
			(at 0 0.4445 270)
			(size 0.1524 0.1524)
			(layers "B.Cu" "B.Mask" "B.Paste")
			(net "P3V3_STBY")
			(options
				(clearance outline)
				(anchor circle)
			)
			(primitives
				(gr_poly
					(pts
						(arc
							(start 0.3048 0.2032)
							(mid 0.275042 0.275042)
							(end 0.2032 0.3048)
						)
						(arc
							(start -0.2032 0.3048)
							(mid -0.275042 0.275042)
							(end -0.3048 0.2032)
						)
						(arc
							(start -0.3048 -0.2032)
							(mid -0.275042 -0.275042)
							(end -0.2032 -0.3048)
						)
						(arc
							(start 0.2032 -0.3048)
							(mid 0.275042 -0.275042)
							(end 0.3048 -0.2032)
						)
					)
					(width 0)
					(fill yes)
				)
			)
		)
	)
	(footprint ""
		(layer "B.Cu")
		(at 9.1186 -70.739 -90)
		(property "Reference" "C624"
			(at 0 0 90)
			(layer "B.SilkS")
			(hide yes)
			(effects
				(font
					(size 1.27 1.27)
				)
				(justify mirror)
			)
		)
		(property "Value" "SC10U6D3V5KX-4GP"
			(at 0.0762 -6.1214 270)
			(unlocked yes)
			(layer "B.Fab")
			(hide yes)
			(effects
				(font
					(size 1.016 1.016)
					(thickness 0.1524)
				)
				(justify mirror)
			)
		)
		(property "Device Type" "C805H58"
			(at 0.0762 -8.1534 270)
			(unlocked yes)
			(layer "B.Fab")
			(hide yes)
			(effects
				(font
					(size 1.016 1.016)
					(thickness 0.1524)
				)
				(justify mirror)
			)
		)
		(duplicate_pad_numbers_are_jumpers no)
		(fp_line
			(start -0.635 0)
			(end 0.635 0)
			(stroke
				(width 0.508)
				(type default)
			)
			(layer "B.SilkS")
		)
		(fp_rect
			(start 0.9652 1.778)
			(end -0.9652 -1.778)
			(stroke
				(width 0)
				(type default)
			)
			(fill no)
			(layer "B.CrtYd")
		)
		(fp_poly
			(pts
				(xy 0.9652 -1.778) (xy -0.9652 -1.778) (xy -0.9652 1.778) (xy 0.9652 1.778)
			)
			(stroke
				(width 0)
				(type default)
			)
			(fill no)
			(layer "B.Fab")
		)
		(pad "1" smd rect
			(at 0 -0.9652 90)
			(size 1.397 1.143)
			(layers "B.Cu" "B.Mask" "B.Paste")
			(net "P1V5_I210")
		)
		(pad "2" smd rect
			(at 0 0.9652 90)
			(size 1.397 1.143)
			(layers "B.Cu" "B.Mask" "B.Paste")
			(net "GND")
		)
	)
	(footprint ""
		(layer "B.Cu")
		(at 247.599962 -39.99992)
		(property "Reference" "TP289"
			(at 0 0 0)
			(layer "B.SilkS")
			(hide yes)
			(effects
				(font
					(size 1.27 1.27)
				)
				(justify mirror)
			)
		)
		(property "Value" "TPAD28-2-GP"
			(at 0.0127 -1.6637 0)
			(unlocked yes)
			(layer "B.Fab")
			(hide yes)
			(effects
				(font
					(size 1.016 1.016)
					(thickness 0.1524)
				)
				(justify mirror)
			)
		)
		(property "Device Type" "TPAD28"
			(at 0.0127 -3.1877 0)
			(unlocked yes)
			(layer "B.Fab")
			(hide yes)
			(effects
				(font
					(size 1.016 1.016)
					(thickness 0.1524)
				)
				(justify mirror)
			)
		)
		(duplicate_pad_numbers_are_jumpers no)
		(fp_poly
			(pts
				(arc
					(start 0.3556 0)
					(mid -0.3556 0)
					(end 0.3556 0)
				)
			)
			(stroke
				(width 0)
				(type default)
			)
			(fill no)
			(layer "B.CrtYd")
		)
		(fp_poly
			(pts
				(arc
					(start 0.6096 0)
					(mid -0.6096 0)
					(end 0.6096 0)
				)
			)
			(stroke
				(width 0)
				(type default)
			)
			(fill no)
			(layer "B.Fab")
		)
		(pad "1" smd circle
			(at 0 0 180)
			(size 0.7112 0.7112)
			(layers "B.Cu" "B.Mask" "B.Paste")
			(net "TWI_SCL6")
		)
	)
	(footprint ""
		(layer "B.Cu")
		(at 245.599966 -33.999932)
		(property "Reference" "TP283"
			(at 0 0 0)
			(layer "B.SilkS")
			(hide yes)
			(effects
				(font
					(size 1.27 1.27)
				)
				(justify mirror)
			)
		)
		(property "Value" "TPAD28-2-GP"
			(at 0.0127 -1.6637 0)
			(unlocked yes)
			(layer "B.Fab")
			(hide yes)
			(effects
				(font
					(size 1.016 1.016)
					(thickness 0.1524)
				)
				(justify mirror)
			)
		)
		(property "Device Type" "TPAD28"
			(at 0.0127 -3.1877 0)
			(unlocked yes)
			(layer "B.Fab")
			(hide yes)
			(effects
				(font
					(size 1.016 1.016)
					(thickness 0.1524)
				)
				(justify mirror)
			)
		)
		(duplicate_pad_numbers_are_jumpers no)
		(fp_poly
			(pts
				(arc
					(start 0.3556 0)
					(mid -0.3556 0)
					(end 0.3556 0)
				)
			)
			(stroke
				(width 0)
				(type default)
			)
			(fill no)
			(layer "B.CrtYd")
		)
		(fp_poly
			(pts
				(arc
					(start 0.6096 0)
					(mid -0.6096 0)
					(end 0.6096 0)
				)
			)
			(stroke
				(width 0)
				(type default)
			)
			(fill no)
			(layer "B.Fab")
		)
		(pad "1" smd circle
			(at 0 0 180)
			(size 0.7112 0.7112)
			(layers "B.Cu" "B.Mask" "B.Paste")
			(net "TWI_SRST#4")
		)
	)
	(footprint ""
		(layer "B.Cu")
		(at 122.1232 -203.835)
		(property "Reference" "R147"
			(at 0 0 0)
			(layer "B.SilkS")
			(hide yes)
			(effects
				(font
					(size 1.27 1.27)
				)
				(justify mirror)
			)
		)
		(property "Value" "4K7R2F-GP"
			(at -0.064008 -3.993896 0)
			(unlocked yes)
			(layer "B.Fab")
			(hide yes)
			(effects
				(font
					(size 1.016 1.016)
					(thickness 0.1524)
				)
				(justify mirror)
			)
		)
		(property "Device Type" "R402H16"
			(at -0.064008 -5.517896 0)
			(unlocked yes)
			(layer "B.Fab")
			(hide yes)
			(effects
				(font
					(size 1.016 1.016)
					(thickness 0.1524)
				)
				(justify mirror)
			)
		)
		(duplicate_pad_numbers_are_jumpers no)
		(fp_line
			(start -0.508 -0.9398)
			(end 0.508 -0.9398)
			(stroke
				(width 0.1524)
				(type default)
			)
			(layer "B.SilkS")
		)
		(fp_line
			(start 0.508 -0.9398)
			(end 0.508 0.9398)
			(stroke
				(width 0.1524)
				(type default)
			)
			(layer "B.SilkS")
		)
		(fp_rect
			(start 0.508 0.9398)
			(end -0.508 -0.9398)
			(stroke
				(width 0)
				(type default)
			)
			(fill no)
			(layer "B.CrtYd")
		)
		(fp_rect
			(start 0.508 0.9398)
			(end -0.508 -0.9398)
			(stroke
				(width 0)
				(type default)
			)
			(fill no)
			(layer "B.Fab")
		)
		(pad "1" smd custom
			(at 0 -0.4445 180)
			(size 0.1397 0.1397)
			(layers "B.Cu" "B.Mask" "B.Paste")
			(net "BMC_SSD_RST#0_A7")
			(options
				(clearance outline)
				(anchor circle)
			)
			(primitives
				(gr_poly
					(pts
						(arc
							(start -0.1778 0.2794)
							(mid -0.249642 0.249642)
							(end -0.2794 0.1778)
						)
						(arc
							(start -0.2794 -0.1778)
							(mid -0.249642 -0.249642)
							(end -0.1778 -0.2794)
						)
						(arc
							(start 0.1778 -0.2794)
							(mid 0.249642 -0.249642)
							(end 0.2794 -0.1778)
						)
						(arc
							(start 0.2794 0.1778)
							(mid 0.249642 0.249642)
							(end 0.1778 0.2794)
						)
					)
					(width 0)
					(fill yes)
				)
			)
		)
		(pad "2" smd custom
			(at 0 0.4445 180)
			(size 0.1397 0.1397)
			(layers "B.Cu" "B.Mask" "B.Paste")
			(net "P3V3_STBY")
			(options
				(clearance outline)
				(anchor circle)
			)
			(primitives
				(gr_poly
					(pts
						(arc
							(start -0.1778 0.2794)
							(mid -0.249642 0.249642)
							(end -0.2794 0.1778)
						)
						(arc
							(start -0.2794 -0.1778)
							(mid -0.249642 -0.249642)
							(end -0.1778 -0.2794)
						)
						(arc
							(start 0.1778 -0.2794)
							(mid 0.249642 -0.249642)
							(end 0.2794 -0.1778)
						)
						(arc
							(start 0.2794 0.1778)
							(mid 0.249642 0.249642)
							(end 0.1778 0.2794)
						)
					)
					(width 0)
					(fill yes)
				)
			)
		)
	)
)
